PARTS LIST

78.10421.2FL       C402H22                   C1
78.10521.2BL       C603H36                   C2
78.10521.2BL       C603H36                   C3
78.10521.2BL       C603H36                   C4
78.10421.2FL       C402H22                   C5
78.10421.2FL       C402H22                   C6
78.10521.2BL       C603H36                   C7
78.10521.2BL       C603H36                   C8
78.10521.2BL       C603H36                   C9
78.10421.2FL       C402H22                   C10
78.10521.2BL       C603H36                   C11
78.10421.2FL       C402H22                   C12
78.10521.2BL       C603H36                   C13
78.10421.2FL       C402H22                   C14
78.10421.2FL       C402H22                   C15
078.1022S.022L     C1206H58                  C16
078.1022S.022L     C1206H58                  C17
78.10421.2FL       C402H22                   C18
78.10421.2FL       C402H22                   C19
78.10421.2FL       C402H22                   C20
78.10421.2FL       C402H22                   C21
78.10421.2FL       C402H22                   C22
78.10421.2FL       C402H22                   C23
78.10421.2FL       C402H22                   C24
78.10421.2FL       C402H22                   C25
78.10421.2FL       C402H22                   C26
78.10421.2FL       C402H22                   C27
78.10421.2FL       C402H22                   C28
78.10421.2FL       C402H22                   C29
78.10421.2FL       C402H22                   C30
78.10421.2FL       C402H22                   C31
78.10421.2FL       C402H22                   C32
78.10421.2FL       C402H22                   C33
78.10421.2FL       C402H22                   C34
020.F0948.0029     SASM2130081TR             CN1
075.3V3L4.0070     SOT-23-5-3H24             D1
075.3V3L4.0070     SOT-23-5-3H24             D2
75.005V0.A77       SOD882-10D6-1H20          D3
75.005V0.A77       SOD882-10D6-1H20          D4
083.5V0X1.00AF     SOD523AKH26               D7
083.5V0X1.00AF     SOD523AKH26               D8
083.5V0X1.00AF     SOD523AKH26               D9
083.5V0X1.00AF     SOD523AKH26               D10
68.00084.A61       L20125H42                 L1
68.00084.A61       L20125H42                 L3
006.03870.0140     LED-100-4035-1A2KH274     LED1
006.03870.0140     LED-100-4035-1A2KH274     LED2
64.10025.6DL       R402H16                   R1
63.R0034.1DL       R402H16                   R2
63.R0034.1DL       R402H16                   R3
64.47015.6DL       R402H16                   R4
63.R0034.1DL       R402H16                   R5
64.47015.6DL       R402H16                   R6
63.R0034.1DL       R402H16                   R7
64.10025.6DL       R402H16                   R8
63.R0034.1DL       R402H16                   R9
63.R0034.1DL       R402H16                   R10
64.47015.6DL       R402H16                   R11
63.R0034.1DL       R402H16                   R12
64.47015.6DL       R402H16                   R13
63.R0034.1DL       R402H16                   R14
63.20134.1DL       R402H16                   R15
63.R0034.1DL       R402H16                   R16
63.R0034.1DL       R402H16                   R17
63.20134.1DL       R402H16                   R18
63.R0034.1DL       R402H16                   R19
63.R0034.1DL       R402H16                   R20
64.22025.6DL       R402H16                   R21
64.22025.6DL       R402H16                   R23
63.12133.15L       R603H22                   R25
63.12133.15L       R603H22                   R26
64.47015.6DL       R402H16                   R27
64.47015.6DL       R402H16                   R28
64.47015.6DL       R402H16                   R29
63.R0034.1DL       R402H16                   R30
63.R0034.1DL       R402H16                   R31
64.47015.6DL       R402H16                   R32
64.47015.6DL       R402H16                   R33
64.47015.6DL       R402H16                   R34
64.47015.6DL       R402H16                   R35
64.47015.6DL       R402H16                   R36
64.47015.6DL       R402H16                   R37
63.R0034.1DL       R402H16                   R38
63.R0034.1DL       R402H16                   R39
64.47015.6DL       R402H16                   R40
64.47015.6DL       R402H16                   R41
64.47015.6DL       R402H16                   R42
64.10045.6DL       R402H16                   R45
64.10045.6DL       R402H16                   R46
64.10035.6DL       R402H16                   R47
64.47015.6DL       R402H16                   R48
64.10015.6DL       R402H16                   R49
64.47015.6DL       R402H16                   R50
64.10035.6DL       R402H16                   R51
64.10015.6DL       R402H16                   R52
64.47015.6DL       R402H16                   R53
64.47015.6DL       R402H16                   R54
64.20025.6DL       R402H16                   R55
64.20025.6DL       R402H16                   R56
64.20025.6DL       R402H16                   R57
64.20025.6DL       R402H16                   R58
64.10035.6DL       R402H16                   R59
64.10035.6DL       R402H16                   R60
64.47015.6DL       R402H16                   R61
64.47015.6DL       R402H16                   R62
64.47015.6DL       R402H16                   R63
64.47015.6DL       R402H16                   R64
64.47015.6DL       R402H16                   R65
64.47015.6DL       R402H16                   R66
64.47015.6DL       R402H16                   R67
64.47015.6DL       R402H16                   R68
64.47015.6DL       R402H16                   R69
64.47015.6DL       R402H16                   R70
64.47015.6DL       R402H16                   R71
64.47015.6DL       R402H16                   R72
64.47015.6DL       R402H16                   R73
64.47015.6DL       R402H16                   R74
63.R0034.1DL       R402H16                   R75
63.R0034.1DL       R402H16                   R76
64.47015.6DL       R402H16                   R77
64.47015.6DL       R402H16                   R78
64.47015.6DL       R402H16                   R79
64.47015.6DL       R402H16                   R80
086.2AT24.04R6     STFT363B238R224H453       SCW1
022.40001.00B1     PS004-L22NPR1KKK3UBXX     SW1
022.40001.00B1     PS004-L22NPR1KKK3UBXX     SW2
062.40001.0521     DTSM-62N-Q-TR             SW3
062.40001.0521     DTSM-62N-Q-TR             SW4
ZZ.PAD28.XXX       TPAD28                    TP1
ZZ.PAD28.XXX       TPAD28                    TP2
ZZ.PAD28.XXX       TPAD28                    TP4
ZZ.PAD28.XXX       TPAD28                    TP5
ZZ.0TPAD.191       TPAD32                    TP7
ZZ.0TPAD.191       TPAD32                    TP8
74.23157.A99       MSOP10H44                 U1
071.09555.000W     TSOIC24H48                U2
74.23157.A99       MSOP10H44                 U3
071.09555.000W     TSOIC24H48                U4
074.03422.0073     XSON6H24                  U5
074.03422.0073     XSON6H24                  U6
74.00075.B79       MSOP8-1H44                U7
74.00075.B79       MSOP8-1H44                U8
71.09306.00I       SSOIC8H52                 U9
73.1G126.DHG       SC70-5H44                 U10
73.1G126.DHG       SC70-5H44                 U11
71.09306.00I       SSOIC8H52                 U12
73.1G126.DHG       SC70-5H44                 U13
73.1G126.DHG       SC70-5H44                 U14
73.01G08.L03       SC70-5H44                 U15
73.01G08.L03       SC70-5H44                 U16
073.01G74.0001     SSOIC8-4H36               U19
073.01G74.0001     SSOIC8-4H36               U20
022.10005.0D41     SKT-USB13-148074-5        USB1
022.10005.0D41     SKT-USB13-148074-5        USB2

EOS

POSITION

C1        392.00      486.00     270.000    TOP
C2         95.97     2550.79     270.000    TOP
C3         95.97     2503.27     270.000    TOP
C4         95.93     2455.66     270.000    TOP
C5        384.00      588.00     270.000    TOP
C6       1835.00      415.00     180.000    TOP
C7       1956.54     2860.24     180.000    TOP
C8       1910.54     2860.24     180.000    TOP
C9       1864.54     2860.24     180.000    TOP
C10      1977.60      550.27       0.000    TOP
C11       195.98     1547.67      90.000    TOP
C12       325.42     1035.42      90.000    TOP
C13      2155.20     1435.00       0.000    TOP
C14       508.18     1993.84      90.000    TOP
C15      2127.00     2019.00     270.000    TOP
C16       305.00     2770.00     270.000    TOP
C17      2082.90     2761.28      90.000    TOP
C18      2166.00     1152.00      90.000    TOP
C19       399.00      823.00     180.000    TOP
C20       159.00      846.00     180.000    TOP
C21       526.00      253.00       0.000    TOP
C22       579.00      386.00     270.000    TOP
C23      1927.24      790.30       0.000    TOP
C24      1689.66      852.30     180.000    TOP
C25      1763.00      422.00     180.000    TOP
C26      1631.00      482.00     270.000    TOP
C27       555.00     1183.00      90.000    TOP
C28      2158.00     1058.10       0.000    TOP
C29      1009.00      424.00     180.000    TOP
C30      1326.00      359.00     180.000    TOP
C31      1043.00      267.00       0.000    TOP
C32      1326.00      488.00     180.000    TOP
C33      1078.00      518.00      90.000    TOP
C34      1183.00      274.00      90.000    TOP
CN1      1163.39       51.18     180.000    TOP
D1        145.69     1703.27       0.000    TOP
D2       2158.21     2240.80       0.000    TOP
D3         79.85     2239.87       0.000    TOP
D4       1787.41     2841.99     180.000    TOP
D7        153.00     2856.50     180.000    TOP
D8       2221.89     3132.31     180.000    TOP
D9        177.00     1092.50       0.000    TOP
D10      1889.00     1157.00      90.000    TOP
L1        111.03     2358.47     180.000    TOP
L3       1825.20     2764.81      90.000    TOP
LED1      322.83     1732.28      90.000    TOP
LED2     1885.83     1732.28      90.000    TOP
R1        765.00      529.00       0.000    TOP
R2        806.00      529.00       0.000    TOP
R3        774.00      470.00      90.000    TOP
R4        121.00      755.00     180.000    TOP
R5        352.00      626.00     270.000    TOP
R6        121.00      830.00       0.000    TOP
R7        500.00      597.00     270.000    TOP
R8       2095.22      505.12     180.000    TOP
R9       2153.00      549.00       0.000    TOP
R10      2189.82      491.39      90.000    TOP
R11      1711.87      701.36     270.000    TOP
R12      2015.00      505.00       0.000    TOP
R13      1689.36      777.13       0.000    TOP
R14      2055.00      505.00       0.000    TOP
R15       502.72     2867.72     180.000    TOP
R16      1099.00      249.00      90.000    TOP
R17      1240.00      540.00     270.000    TOP
R18      2207.23     2896.45     180.000    TOP
R19       993.01      325.37     270.000    TOP
R20      1317.00      240.00      90.000    TOP
R21       491.62     1541.67      90.000    TOP
R23      2155.16     1340.85     180.000    TOP
R25       366.09     1597.38     270.000    TOP
R26      1915.83     1565.00     270.000    TOP
R27       465.00     1916.10     270.000    TOP
R28       465.00     1876.10      90.000    TOP
R29       483.00     1738.00       0.000    TOP
R30        72.00     2010.00       0.000    TOP
R31        90.50     1935.00       0.000    TOP
R32       465.00     1956.10      90.000    TOP
R33       544.92     1836.24       0.000    TOP
R34       524.00     1738.00     180.000    TOP
R35      2161.00     2067.00      90.000    TOP
R36      2232.00     1946.00     180.000    TOP
R37      2174.00     1813.00      90.000    TOP
R38      2055.00     1744.00       0.000    TOP
R39      2099.00     1744.00       0.000    TOP
R40      2174.00     1973.00      90.000    TOP
R41      2232.00     1870.50     180.000    TOP
R42      2174.00     1853.00     270.000    TOP
R45       320.00     2840.00     270.000    TOP
R46      2088.67     2834.48      90.000    TOP
R47       233.00     1075.00     180.000    TOP
R48       397.42     1093.58     270.000    TOP
R49       282.00     1196.00       0.000    TOP
R50       400.00     1185.00      90.000    TOP
R51      2002.20     1136.00     270.000    TOP
R52      1944.71     1215.00     270.000    TOP
R53      2188.32     1265.59       0.000    TOP
R54      2166.00     1190.00      90.000    TOP
R55       314.00      708.00     270.000    TOP
R56       239.00      708.00      90.000    TOP
R57      1865.00      702.00     270.000    TOP
R58      1790.00      702.00      90.000    TOP
R59       550.00      323.00      90.000    TOP
R60      1726.00      488.00      90.000    TOP
R61       718.00      605.00     270.000    TOP
R62       352.31      667.04      90.000    TOP
R63       792.00      718.00       0.000    TOP
R64       796.04      820.69       0.000    TOP
R65       390.31      708.04     270.000    TOP
R66       792.00      643.00       0.000    TOP
R67       756.04      820.69     180.000    TOP
R68      2195.00      549.00     180.000    TOP
R69      1882.50      607.96       0.000    TOP
R70      1925.00      685.00     180.000    TOP
R71      2225.00      405.00       0.000    TOP
R72      2183.00      375.00     180.000    TOP
R73      2193.78      276.05       0.000    TOP
R74      2153.78      276.05     180.000    TOP
R75       337.00     1198.00       0.000    TOP
R76      1808.00     1066.00     180.000    TOP
R77       375.00      914.00      90.000    TOP
R78      1905.00      900.00      90.000    TOP
R79       980.71      499.25     180.000    TOP
R80      1183.00      235.00     270.000    TOP
SCW1     1163.39      787.40      90.000    TOP
SW1       322.83     3129.92       0.000    TOP
SW2      1925.20     3129.92       0.000    TOP
SW3       322.83     1377.95       0.000    TOP
SW4      1925.20     1377.95       0.000    TOP
TP1       105.19     2174.35      90.000    TOP
TP2        83.92     2078.60      90.000    TOP
TP4      1786.95     1851.53      90.000    TOP
TP5      1785.63     1970.14      90.000    TOP
TP7       132.00     1879.00      90.000    TOP
TP8      1836.53     1910.58       0.000    TOP
U1        563.00      495.00      90.000    TOP
U2        584.00      795.00      90.000    TOP
U3       1990.00      385.00      90.000    TOP
U4       2095.00      755.00      90.000    TOP
U5        302.79     1102.52      90.000    TOP
U6       2087.55     1174.00      90.000    TOP
U7        291.00     1930.00     270.000    TOP
U8       1995.00     1921.00     270.000    TOP
U9        280.00      805.00     270.000    TOP
U10       445.00      292.00       0.000    TOP
U11       650.00      290.00     180.000    TOP
U12      1810.00      795.00     270.000    TOP
U13      1667.02      380.82      90.000    TOP
U14      1675.00      570.00     270.000    TOP
U15       550.00     1105.00      90.000    TOP
U16      2063.00     1055.00      90.000    TOP
U19      1090.03      402.85       0.000    TOP
U20      1248.15      389.91     180.000    TOP
USB1      322.83     2362.20      90.000    TOP
USB2     1925.20     2362.20      90.000    TOP

EOS

#From(Function(Sicard.Report) Version 3.0)